(kicad_pcb
	(version 20260206)
	(generator "pcbnew")
	(generator_version "10.0")
	(general
		(thickness 1.6)
		(legacy_teardrops no)
	)
	(paper "A4")
	(title_block
		(title "12092022_DA0F0TMDCD0_F0T_Management_Board_D_brd_V3_OCP.brd")
		(comment 1 "Grand Teton / footprints 1076-1081 of 1440")
	)
	(layers
		(0 "F.Cu" signal "TOP")
		(4 "In1.Cu" signal "GND")
		(6 "In2.Cu" signal "IN1")
		(8 "In3.Cu" signal "GND1")
		(10 "In4.Cu" signal "IN2")
		(12 "In5.Cu" signal "VCC")
		(14 "In6.Cu" signal "VCC1")
		(16 "In7.Cu" signal "IN3")
		(18 "In8.Cu" signal "GND2")
		(20 "In9.Cu" signal "IN4")
		(22 "In10.Cu" signal "GND3")
		(2 "B.Cu" signal "BOTTOM")
		(9 "F.Adhes" user "F.Adhesive")
		(11 "B.Adhes" user "B.Adhesive")
		(13 "F.Paste" user "Package Geometry/Pastemask Top")
		(15 "B.Paste" user "Package Geometry/Pastemask Bottom")
		(5 "F.SilkS" user "Ref Des/Silkscreen Top")
		(7 "B.SilkS" user "Ref Des/Silkscreen Bottom")
		(1 "F.Mask" user "Board Geometry/Soldermask Top")
		(3 "B.Mask" user "Board Geometry/Soldermask Bottom")
		(17 "Dwgs.User" user "User.Drawings")
		(19 "Cmts.User" user "User.Comments")
		(21 "Eco1.User" user "User.Eco1")
		(23 "Eco2.User" user "User.Eco2")
		(25 "Edge.Cuts" user "Board Geometry/Outline")
		(27 "Margin" user)
		(31 "F.CrtYd" user "Package Geometry/Place Bound Top")
		(29 "B.CrtYd" user "Package Geometry/Place Bound Bottom")
		(35 "F.Fab" user "Ref Des/Assembly Top")
		(33 "B.Fab" user "Ref Des/Assembly Bottom")
	)
	(footprint ""
		(layer "B.Cu")
		(at 29.591 -20.6502 -90)
		(property "Reference" "D16"
			(at 5.0292 0.02667 270)
			(unlocked yes)
			(layer "B.SilkS")
			(effects
				(font
					(size 0.7874 0.5842)
					(thickness 0.1524)
				)
				(justify left mirror)
			)
		)
		(property "Value" ""
			(at 0 0 90)
			(layer "B.Fab")
			(effects
				(font
					(size 1.27 1.27)
				)
				(justify mirror)
			)
		)
		(duplicate_pad_numbers_are_jumpers no)
		(fp_line
			(start -1.3208 0.635)
			(end 1.056894 0.635)
			(stroke
				(width 0.1524)
				(type default)
			)
			(layer "B.SilkS")
		)
		(fp_line
			(start 1.056894 0.635)
			(end 1.056894 -0.635)
			(stroke
				(width 0.1524)
				(type default)
			)
			(layer "B.SilkS")
		)
		(fp_line
			(start -1.3208 -0.635)
			(end -1.3208 0.635)
			(stroke
				(width 0.1524)
				(type default)
			)
			(layer "B.SilkS")
		)
		(fp_line
			(start -1.3208 -0.635)
			(end -1.3208 0.635)
			(stroke
				(width 0.1524)
				(type default)
			)
			(layer "B.SilkS")
		)
		(fp_line
			(start -1.27 -0.635)
			(end -1.27 0.635)
			(stroke
				(width 0.1524)
				(type default)
			)
			(layer "B.SilkS")
		)
		(fp_line
			(start -1.1684 -0.635)
			(end -1.1684 0.635)
			(stroke
				(width 0.1524)
				(type default)
			)
			(layer "B.SilkS")
		)
		(fp_line
			(start -1.0668 -0.635)
			(end -1.0668 0.635)
			(stroke
				(width 0.1524)
				(type default)
			)
			(layer "B.SilkS")
		)
		(fp_line
			(start 1.056894 -0.635)
			(end -1.3208 -0.635)
			(stroke
				(width 0.1524)
				(type default)
			)
			(layer "B.SilkS")
		)
		(fp_line
			(start -0.824992 0.525018)
			(end -0.824992 -0.525018)
			(stroke
				(width 0.1)
				(type default)
			)
			(layer "B.Fab")
		)
		(fp_line
			(start 0.824992 0.525018)
			(end -0.824992 0.525018)
			(stroke
				(width 0.1)
				(type default)
			)
			(layer "B.Fab")
		)
		(fp_line
			(start -0.824992 -0.525018)
			(end 0.824992 -0.525018)
			(stroke
				(width 0.1)
				(type default)
			)
			(layer "B.Fab")
		)
		(fp_line
			(start 0.824992 -0.525018)
			(end 0.824992 0.525018)
			(stroke
				(width 0.1)
				(type default)
			)
			(layer "B.Fab")
		)
		(fp_text user "+"
			(at 2.3622 -0.22225 270)
			(unlocked yes)
			(layer "B.SilkS")
			(effects
				(font
					(size 1.905 1.4224)
					(thickness 0.1524)
				)
				(justify left mirror)
			)
		)
		(fp_text user "-"
			(at -1.3716 -0.27305 270)
			(unlocked yes)
			(layer "B.SilkS")
			(effects
				(font
					(size 1.905 1.4224)
					(thickness 0.1524)
				)
				(justify left mirror)
			)
		)
		(fp_text user "+"
			(at 2.3622 -0.22225 270)
			(unlocked yes)
			(layer "B.Fab")
			(effects
				(font
					(size 1.905 1.4224)
					(thickness 0.1524)
				)
				(justify left mirror)
			)
		)
		(fp_text user "-"
			(at -1.3716 -0.27305 270)
			(unlocked yes)
			(layer "B.Fab")
			(effects
				(font
					(size 1.905 1.4224)
					(thickness 0.1524)
				)
				(justify left mirror)
			)
		)
		(pad "1" smd rect
			(at 0.612394 0 90)
			(size 0.635 1.016)
			(layers "B.Cu" "B.Mask" "B.Paste")
			(net "P5V_AUX")
		)
		(pad "2" smd rect
			(at -0.612394 0 90)
			(size 0.635 1.016)
			(layers "B.Cu" "B.Mask" "B.Paste")
			(net "CRT_VCC5_2_D")
		)
	)
	(footprint ""
		(layer "B.Cu")
		(at 49.868328 -36.935664 -90)
		(property "Reference" "R151"
			(at 0 0 90)
			(layer "B.SilkS")
			(hide yes)
			(effects
				(font
					(size 1.27 1.27)
				)
				(justify mirror)
			)
		)
		(property "Value" ""
			(at 0 0 90)
			(layer "B.Fab")
			(effects
				(font
					(size 1.27 1.27)
				)
				(justify mirror)
			)
		)
		(duplicate_pad_numbers_are_jumpers no)
		(fp_line
			(start -0.7874 0.4064)
			(end 0.7874 0.4064)
			(stroke
				(width 0.1524)
				(type default)
			)
			(layer "B.SilkS")
		)
		(fp_line
			(start 0.7874 0.4064)
			(end 0.7874 -0.4064)
			(stroke
				(width 0.1524)
				(type default)
			)
			(layer "B.SilkS")
		)
		(fp_line
			(start -0.7874 -0.4064)
			(end -0.7874 0.4064)
			(stroke
				(width 0.1524)
				(type default)
			)
			(layer "B.SilkS")
		)
		(fp_line
			(start 0.7874 -0.4064)
			(end -0.7874 -0.4064)
			(stroke
				(width 0.1524)
				(type default)
			)
			(layer "B.SilkS")
		)
		(fp_line
			(start -0.67945 0.3048)
			(end -0.120396 0.3048)
			(stroke
				(width 0.1)
				(type default)
			)
			(layer "B.Fab")
		)
		(fp_line
			(start -0.120396 0.3048)
			(end -0.120396 0.2794)
			(stroke
				(width 0.1)
				(type default)
			)
			(layer "B.Fab")
		)
		(fp_line
			(start 0.12065 0.3048)
			(end 0.67945 0.3048)
			(stroke
				(width 0.1)
				(type default)
			)
			(layer "B.Fab")
		)
		(fp_line
			(start 0.67945 0.3048)
			(end 0.67945 -0.305054)
			(stroke
				(width 0.1)
				(type default)
			)
			(layer "B.Fab")
		)
		(fp_line
			(start -0.120396 0.2794)
			(end 0.12065 0.2794)
			(stroke
				(width 0.1)
				(type default)
			)
			(layer "B.Fab")
		)
		(fp_line
			(start 0.12065 0.2794)
			(end 0.12065 0.3048)
			(stroke
				(width 0.1)
				(type default)
			)
			(layer "B.Fab")
		)
		(fp_line
			(start -0.12065 -0.2794)
			(end -0.12065 -0.3048)
			(stroke
				(width 0.1)
				(type default)
			)
			(layer "B.Fab")
		)
		(fp_line
			(start 0.12065 -0.2794)
			(end -0.12065 -0.2794)
			(stroke
				(width 0.1)
				(type default)
			)
			(layer "B.Fab")
		)
		(fp_line
			(start -0.67945 -0.3048)
			(end -0.67945 0.3048)
			(stroke
				(width 0.1)
				(type default)
			)
			(layer "B.Fab")
		)
		(fp_line
			(start -0.12065 -0.3048)
			(end -0.67945 -0.3048)
			(stroke
				(width 0.1)
				(type default)
			)
			(layer "B.Fab")
		)
		(fp_line
			(start 0.12065 -0.305054)
			(end 0.12065 -0.2794)
			(stroke
				(width 0.1)
				(type default)
			)
			(layer "B.Fab")
		)
		(fp_line
			(start 0.67945 -0.305054)
			(end 0.12065 -0.305054)
			(stroke
				(width 0.1)
				(type default)
			)
			(layer "B.Fab")
		)
		(pad "1" smd circle
			(at 0.40005 0 90)
			(size 0 0)
			(layers "B.Cu" "B.Mask" "B.Paste")
			(net "SGPIO_DO_1")
		)
		(pad "2" smd circle
			(at -0.40005 0 90)
			(size 0 0)
			(layers "B.Cu" "B.Mask" "B.Paste")
			(net "SGPIO_BMC_M1_DO")
		)
	)
	(footprint ""
		(layer "B.Cu")
		(at 77.598778 -48.63084 -90)
		(property "Reference" "C229"
			(at 0 0 90)
			(layer "B.SilkS")
			(hide yes)
			(effects
				(font
					(size 1.27 1.27)
				)
				(justify mirror)
			)
		)
		(property "Value" ""
			(at 0 0 90)
			(layer "B.Fab")
			(effects
				(font
					(size 1.27 1.27)
				)
				(justify mirror)
			)
		)
		(duplicate_pad_numbers_are_jumpers no)
		(fp_line
			(start -0.7874 0.4064)
			(end 0.7874 0.4064)
			(stroke
				(width 0.1524)
				(type default)
			)
			(layer "B.SilkS")
		)
		(fp_line
			(start 0.7874 0.4064)
			(end 0.7874 -0.4064)
			(stroke
				(width 0.1524)
				(type default)
			)
			(layer "B.SilkS")
		)
		(fp_line
			(start -0.7874 -0.4064)
			(end -0.7874 0.4064)
			(stroke
				(width 0.1524)
				(type default)
			)
			(layer "B.SilkS")
		)
		(fp_line
			(start 0.7874 -0.4064)
			(end -0.7874 -0.4064)
			(stroke
				(width 0.1524)
				(type default)
			)
			(layer "B.SilkS")
		)
		(fp_line
			(start -0.67945 0.3048)
			(end -0.120396 0.3048)
			(stroke
				(width 0.1)
				(type default)
			)
			(layer "B.Fab")
		)
		(fp_line
			(start -0.120396 0.3048)
			(end -0.120396 0.2794)
			(stroke
				(width 0.1)
				(type default)
			)
			(layer "B.Fab")
		)
		(fp_line
			(start 0.12065 0.3048)
			(end 0.67945 0.3048)
			(stroke
				(width 0.1)
				(type default)
			)
			(layer "B.Fab")
		)
		(fp_line
			(start 0.67945 0.3048)
			(end 0.67945 -0.305054)
			(stroke
				(width 0.1)
				(type default)
			)
			(layer "B.Fab")
		)
		(fp_line
			(start -0.120396 0.2794)
			(end 0.12065 0.2794)
			(stroke
				(width 0.1)
				(type default)
			)
			(layer "B.Fab")
		)
		(fp_line
			(start 0.12065 0.2794)
			(end 0.12065 0.3048)
			(stroke
				(width 0.1)
				(type default)
			)
			(layer "B.Fab")
		)
		(fp_line
			(start -0.12065 -0.2794)
			(end -0.12065 -0.3048)
			(stroke
				(width 0.1)
				(type default)
			)
			(layer "B.Fab")
		)
		(fp_line
			(start 0.12065 -0.2794)
			(end -0.12065 -0.2794)
			(stroke
				(width 0.1)
				(type default)
			)
			(layer "B.Fab")
		)
		(fp_line
			(start -0.67945 -0.3048)
			(end -0.67945 0.3048)
			(stroke
				(width 0.1)
				(type default)
			)
			(layer "B.Fab")
		)
		(fp_line
			(start -0.12065 -0.3048)
			(end -0.67945 -0.3048)
			(stroke
				(width 0.1)
				(type default)
			)
			(layer "B.Fab")
		)
		(fp_line
			(start 0.12065 -0.305054)
			(end 0.12065 -0.2794)
			(stroke
				(width 0.1)
				(type default)
			)
			(layer "B.Fab")
		)
		(fp_line
			(start 0.67945 -0.305054)
			(end 0.12065 -0.305054)
			(stroke
				(width 0.1)
				(type default)
			)
			(layer "B.Fab")
		)
		(pad "1" smd circle
			(at 0.40005 0 90)
			(size 0 0)
			(layers "B.Cu" "B.Mask" "B.Paste")
			(net "M_BMC_DDR4_MCLK_C")
		)
		(pad "2" smd circle
			(at -0.40005 0 90)
			(size 0 0)
			(layers "B.Cu" "B.Mask" "B.Paste")
			(net "P1V2_AUX")
		)
	)
	(footprint ""
		(layer "B.Cu")
		(at 71.979282 -62.776608 90)
		(property "Reference" "C128"
			(at 0 0 90)
			(layer "B.SilkS")
			(hide yes)
			(effects
				(font
					(size 1.27 1.27)
				)
				(justify mirror)
			)
		)
		(property "Value" ""
			(at 0 0 90)
			(layer "B.Fab")
			(effects
				(font
					(size 1.27 1.27)
				)
				(justify mirror)
			)
		)
		(duplicate_pad_numbers_are_jumpers no)
		(fp_line
			(start 0.7874 -0.4064)
			(end -0.7874 -0.4064)
			(stroke
				(width 0.1524)
				(type default)
			)
			(layer "B.SilkS")
		)
		(fp_line
			(start -0.7874 -0.4064)
			(end -0.7874 0.4064)
			(stroke
				(width 0.1524)
				(type default)
			)
			(layer "B.SilkS")
		)
		(fp_line
			(start 0.7874 0.4064)
			(end 0.7874 -0.4064)
			(stroke
				(width 0.1524)
				(type default)
			)
			(layer "B.SilkS")
		)
		(fp_line
			(start -0.7874 0.4064)
			(end 0.7874 0.4064)
			(stroke
				(width 0.1524)
				(type default)
			)
			(layer "B.SilkS")
		)
		(fp_line
			(start 0.67945 -0.305054)
			(end 0.12065 -0.305054)
			(stroke
				(width 0.1)
				(type default)
			)
			(layer "B.Fab")
		)
		(fp_line
			(start 0.12065 -0.305054)
			(end 0.12065 -0.2794)
			(stroke
				(width 0.1)
				(type default)
			)
			(layer "B.Fab")
		)
		(fp_line
			(start -0.12065 -0.3048)
			(end -0.67945 -0.3048)
			(stroke
				(width 0.1)
				(type default)
			)
			(layer "B.Fab")
		)
		(fp_line
			(start -0.67945 -0.3048)
			(end -0.67945 0.3048)
			(stroke
				(width 0.1)
				(type default)
			)
			(layer "B.Fab")
		)
		(fp_line
			(start 0.12065 -0.2794)
			(end -0.12065 -0.2794)
			(stroke
				(width 0.1)
				(type default)
			)
			(layer "B.Fab")
		)
		(fp_line
			(start -0.12065 -0.2794)
			(end -0.12065 -0.3048)
			(stroke
				(width 0.1)
				(type default)
			)
			(layer "B.Fab")
		)
		(fp_line
			(start 0.12065 0.2794)
			(end 0.12065 0.3048)
			(stroke
				(width 0.1)
				(type default)
			)
			(layer "B.Fab")
		)
		(fp_line
			(start -0.120396 0.2794)
			(end 0.12065 0.2794)
			(stroke
				(width 0.1)
				(type default)
			)
			(layer "B.Fab")
		)
		(fp_line
			(start 0.67945 0.3048)
			(end 0.67945 -0.305054)
			(stroke
				(width 0.1)
				(type default)
			)
			(layer "B.Fab")
		)
		(fp_line
			(start 0.12065 0.3048)
			(end 0.67945 0.3048)
			(stroke
				(width 0.1)
				(type default)
			)
			(layer "B.Fab")
		)
		(fp_line
			(start -0.120396 0.3048)
			(end -0.120396 0.2794)
			(stroke
				(width 0.1)
				(type default)
			)
			(layer "B.Fab")
		)
		(fp_line
			(start -0.67945 0.3048)
			(end -0.120396 0.3048)
			(stroke
				(width 0.1)
				(type default)
			)
			(layer "B.Fab")
		)
		(pad "1" smd circle
			(at 0.40005 0 270)
			(size 0 0)
			(layers "B.Cu" "B.Mask" "B.Paste")
			(net "P1V8_STBY_DP_VCC18A")
		)
		(pad "2" smd circle
			(at -0.40005 0 270)
			(size 0 0)
			(layers "B.Cu" "B.Mask" "B.Paste")
			(net "GND")
		)
	)
	(footprint ""
		(layer "B.Cu")
		(at 40.0304 -106.3752 -90)
		(property "Reference" "R228"
			(at 0 0 90)
			(layer "B.SilkS")
			(hide yes)
			(effects
				(font
					(size 1.27 1.27)
				)
				(justify mirror)
			)
		)
		(property "Value" ""
			(at 0 0 90)
			(layer "B.Fab")
			(effects
				(font
					(size 1.27 1.27)
				)
				(justify mirror)
			)
		)
		(duplicate_pad_numbers_are_jumpers no)
		(fp_line
			(start -0.7874 0.4064)
			(end 0.7874 0.4064)
			(stroke
				(width 0.1524)
				(type default)
			)
			(layer "B.SilkS")
		)
		(fp_line
			(start 0.7874 0.4064)
			(end 0.7874 -0.4064)
			(stroke
				(width 0.1524)
				(type default)
			)
			(layer "B.SilkS")
		)
		(fp_line
			(start -0.7874 -0.4064)
			(end -0.7874 0.4064)
			(stroke
				(width 0.1524)
				(type default)
			)
			(layer "B.SilkS")
		)
		(fp_line
			(start 0.7874 -0.4064)
			(end -0.7874 -0.4064)
			(stroke
				(width 0.1524)
				(type default)
			)
			(layer "B.SilkS")
		)
		(fp_line
			(start -0.67945 0.3048)
			(end -0.120396 0.3048)
			(stroke
				(width 0.1)
				(type default)
			)
			(layer "B.Fab")
		)
		(fp_line
			(start -0.120396 0.3048)
			(end -0.120396 0.2794)
			(stroke
				(width 0.1)
				(type default)
			)
			(layer "B.Fab")
		)
		(fp_line
			(start 0.12065 0.3048)
			(end 0.67945 0.3048)
			(stroke
				(width 0.1)
				(type default)
			)
			(layer "B.Fab")
		)
		(fp_line
			(start 0.67945 0.3048)
			(end 0.67945 -0.305054)
			(stroke
				(width 0.1)
				(type default)
			)
			(layer "B.Fab")
		)
		(fp_line
			(start -0.120396 0.2794)
			(end 0.12065 0.2794)
			(stroke
				(width 0.1)
				(type default)
			)
			(layer "B.Fab")
		)
		(fp_line
			(start 0.12065 0.2794)
			(end 0.12065 0.3048)
			(stroke
				(width 0.1)
				(type default)
			)
			(layer "B.Fab")
		)
		(fp_line
			(start -0.12065 -0.2794)
			(end -0.12065 -0.3048)
			(stroke
				(width 0.1)
				(type default)
			)
			(layer "B.Fab")
		)
		(fp_line
			(start 0.12065 -0.2794)
			(end -0.12065 -0.2794)
			(stroke
				(width 0.1)
				(type default)
			)
			(layer "B.Fab")
		)
		(fp_line
			(start -0.67945 -0.3048)
			(end -0.67945 0.3048)
			(stroke
				(width 0.1)
				(type default)
			)
			(layer "B.Fab")
		)
		(fp_line
			(start -0.12065 -0.3048)
			(end -0.67945 -0.3048)
			(stroke
				(width 0.1)
				(type default)
			)
			(layer "B.Fab")
		)
		(fp_line
			(start 0.12065 -0.305054)
			(end 0.12065 -0.2794)
			(stroke
				(width 0.1)
				(type default)
			)
			(layer "B.Fab")
		)
		(fp_line
			(start 0.67945 -0.305054)
			(end 0.12065 -0.305054)
			(stroke
				(width 0.1)
				(type default)
			)
			(layer "B.Fab")
		)
		(pad "1" smd circle
			(at 0.40005 0 90)
			(size 0 0)
			(layers "B.Cu" "B.Mask" "B.Paste")
			(net "GND")
		)
		(pad "2" smd circle
			(at -0.40005 0 90)
			(size 0 0)
			(layers "B.Cu" "B.Mask" "B.Paste")
			(net "JTAG_MB_TCK")
		)
	)
	(footprint ""
		(layer "B.Cu")
		(at 82.108294 -52.746656 180)
		(property "Reference" "C169"
			(at 0 0 0)
			(layer "B.SilkS")
			(hide yes)
			(effects
				(font
					(size 1.27 1.27)
				)
				(justify mirror)
			)
		)
		(property "Value" ""
			(at 0 0 0)
			(layer "B.Fab")
			(effects
				(font
					(size 1.27 1.27)
				)
				(justify mirror)
			)
		)
		(duplicate_pad_numbers_are_jumpers no)
		(fp_line
			(start 0.7874 0.4064)
			(end 0.7874 -0.4064)
			(stroke
				(width 0.1524)
				(type default)
			)
			(layer "B.SilkS")
		)
		(fp_line
			(start 0.7874 -0.4064)
			(end -0.7874 -0.4064)
			(stroke
				(width 0.1524)
				(type default)
			)
			(layer "B.SilkS")
		)
		(fp_line
			(start -0.7874 0.4064)
			(end 0.7874 0.4064)
			(stroke
				(width 0.1524)
				(type default)
			)
			(layer "B.SilkS")
		)
		(fp_line
			(start -0.7874 -0.4064)
			(end -0.7874 0.4064)
			(stroke
				(width 0.1524)
				(type default)
			)
			(layer "B.SilkS")
		)
		(fp_line
			(start 0.67945 0.3048)
			(end 0.67945 -0.305054)
			(stroke
				(width 0.1)
				(type default)
			)
			(layer "B.Fab")
		)
		(fp_line
			(start 0.67945 -0.305054)
			(end 0.12065 -0.305054)
			(stroke
				(width 0.1)
				(type default)
			)
			(layer "B.Fab")
		)
		(fp_line
			(start 0.12065 0.3048)
			(end 0.67945 0.3048)
			(stroke
				(width 0.1)
				(type default)
			)
			(layer "B.Fab")
		)
		(fp_line
			(start 0.12065 0.2794)
			(end 0.12065 0.3048)
			(stroke
				(width 0.1)
				(type default)
			)
			(layer "B.Fab")
		)
		(fp_line
			(start 0.12065 -0.2794)
			(end -0.12065 -0.2794)
			(stroke
				(width 0.1)
				(type default)
			)
			(layer "B.Fab")
		)
		(fp_line
			(start 0.12065 -0.305054)
			(end 0.12065 -0.2794)
			(stroke
				(width 0.1)
				(type default)
			)
			(layer "B.Fab")
		)
		(fp_line
			(start -0.120396 0.3048)
			(end -0.120396 0.2794)
			(stroke
				(width 0.1)
				(type default)
			)
			(layer "B.Fab")
		)
		(fp_line
			(start -0.120396 0.2794)
			(end 0.12065 0.2794)
			(stroke
				(width 0.1)
				(type default)
			)
			(layer "B.Fab")
		)
		(fp_line
			(start -0.12065 -0.2794)
			(end -0.12065 -0.3048)
			(stroke
				(width 0.1)
				(type default)
			)
			(layer "B.Fab")
		)
		(fp_line
			(start -0.12065 -0.3048)
			(end -0.67945 -0.3048)
			(stroke
				(width 0.1)
				(type default)
			)
			(layer "B.Fab")
		)
		(fp_line
			(start -0.67945 0.3048)
			(end -0.120396 0.3048)
			(stroke
				(width 0.1)
				(type default)
			)
			(layer "B.Fab")
		)
		(fp_line
			(start -0.67945 -0.3048)
			(end -0.67945 0.3048)
			(stroke
				(width 0.1)
				(type default)
			)
			(layer "B.Fab")
		)
		(pad "1" smd circle
			(at 0.40005 0)
			(size 0 0)
			(layers "B.Cu" "B.Mask" "B.Paste")
			(net "P1V2_AUX")
		)
		(pad "2" smd circle
			(at -0.40005 0)
			(size 0 0)
			(layers "B.Cu" "B.Mask" "B.Paste")
			(net "P0V6_DDR_VREF_AUX")
		)
	)
)
